# BASEBOARD_FAB2 (Tioga Pass) — schematic netlist excerpt (pin names and nets, part order shuffled) for the footprints in the layout excerpt that follows; sources: Cadence DE-HDL packaged netlist, KiCad conversion of Wiwynn_Tioga_Pass_MB.brd

C4E24  CAPP  470UF 2.5V 20% ALUM  pkg 3018  page 193 : A = PVCCMCP_CPU1 ; B = GND
C4A4  CAP  10UF 16V 10% X7R  pkg 0805  page 197 : A = P12V_NVDIMM_DEF ; B = GND
RT10  1R3F-GP  1%  pkg RCL_GP  page 209 : \1\ = VR_PVCCIN_CPU1_PHASE5_RC ; \2\ = GND

(kicad_pcb
	(version 20260206)
	(generator "pcbnew")
	(generator_version "10.0")
	(general
		(thickness 1.6)
		(legacy_teardrops no)
	)
	(paper "A4")
	(title_block
		(title "Wiwynn_Tioga_Pass_MB.brd")
		(comment 1 "Tioga Pass / footprints 1069-1071 of 4770")
	)
	(layers
		(0 "F.Cu" signal "TOP")
		(4 "In1.Cu" signal "L2GND")
		(6 "In2.Cu" signal "L3")
		(8 "In3.Cu" signal "L4GND")
		(10 "In4.Cu" signal "L5")
		(12 "In5.Cu" signal "L6GND")
		(14 "In6.Cu" signal "L7VCC")
		(16 "In7.Cu" signal "L8VCC")
		(18 "In8.Cu" signal "L9GND")
		(20 "In9.Cu" signal "L10")
		(22 "In10.Cu" signal "L11GND")
		(24 "In11.Cu" signal "L12")
		(26 "In12.Cu" signal "L13GND")
		(2 "B.Cu" signal "BOTTOM")
		(9 "F.Adhes" user "F.Adhesive")
		(11 "B.Adhes" user "B.Adhesive")
		(13 "F.Paste" user "Package Geometry/Pastemask Top")
		(15 "B.Paste" user "Package Geometry/Pastemask Bottom")
		(5 "F.SilkS" user "Ref Des/Silkscreen Top")
		(7 "B.SilkS" user "Ref Des/Silkscreen Bottom")
		(1 "F.Mask" user "Board Geometry/Soldermask Top")
		(3 "B.Mask" user "Board Geometry/Soldermask Bottom")
		(17 "Dwgs.User" user "User.Drawings")
		(19 "Cmts.User" user "User.Comments")
		(21 "Eco1.User" user "User.Eco1")
		(23 "Eco2.User" user "User.Eco2")
		(25 "Edge.Cuts" user "Board Geometry/Outline")
		(27 "Margin" user)
		(31 "F.CrtYd" user "Package Geometry/Place Bound Top")
		(29 "B.CrtYd" user "Package Geometry/Place Bound Bottom")
		(35 "F.Fab" user "Ref Des/Assembly Top")
		(33 "B.Fab" user "Ref Des/Assembly Bottom")
	)
	(footprint ""
		(layer "F.Cu")
		(at 193.127122 -149.778212 -90)
		(property "Reference" "C4A4"
			(at 0 0 270)
			(layer "F.SilkS")
			(hide yes)
			(effects
				(font
					(size 1.27 1.27)
				)
			)
		)
		(property "Value" ""
			(at 0 0 270)
			(layer "F.Fab")
			(effects
				(font
					(size 1.27 1.27)
				)
			)
		)
		(duplicate_pad_numbers_are_jumpers no)
		(fp_rect
			(start -0.7239 1.9939)
			(end 0.7239 -0.2159)
			(stroke
				(width 0)
				(type default)
			)
			(fill no)
			(layer "F.CrtYd")
		)
		(fp_line
			(start -0.7239 1.9939)
			(end 0.7239 1.9939)
			(stroke
				(width 0.1)
				(type default)
			)
			(layer "F.Fab")
		)
		(fp_line
			(start 0.7239 1.9939)
			(end 0.7239 -0.2159)
			(stroke
				(width 0.1)
				(type default)
			)
			(layer "F.Fab")
		)
		(fp_line
			(start -0.7239 -0.2159)
			(end -0.7239 1.9939)
			(stroke
				(width 0.1)
				(type default)
			)
			(layer "F.Fab")
		)
		(fp_line
			(start 0.7239 -0.2159)
			(end -0.7239 -0.2159)
			(stroke
				(width 0.1)
				(type default)
			)
			(layer "F.Fab")
		)
		(pad "1" smd rect
			(at 0 0 270)
			(size 1.27 1.016)
			(layers "F.Cu" "F.Mask" "F.Paste")
			(net "P12V_NVDIMM_DEF")
		)
		(pad "2" smd rect
			(at 0 1.778 270)
			(size 1.27 1.016)
			(layers "F.Cu" "F.Mask" "F.Paste")
			(net "GND")
		)
		(zone
			(layer "F.Cu")
			(hatch none 0.5)
			(connect_pads
				(clearance 0)
			)
			(min_thickness 0.25)
			(keepout
				(tracks not_allowed)
				(vias allowed)
				(pads allowed)
				(copperpour not_allowed)
				(footprints allowed)
			)
			(placement
				(enabled no)
				(sheetname "")
			)
			(fill
				(thermal_gap 0.5)
				(thermal_bridge_width 0.5)
				(island_removal_mode 0)
			)
			(polygon
				(pts
					(xy 191.857122 -150.413212) (xy 191.857122 -149.143212) (xy 192.619122 -149.143212) (xy 192.619122 -150.413212)
				)
			)
		)
	)
	(footprint ""
		(layer "F.Cu")
		(at 182.118 -47.8282 -90)
		(property "Reference" "C4E24"
			(at 2.05867 9.652 0)
			(unlocked yes)
			(layer "F.SilkS")
			(effects
				(font
					(size 0.7874 0.5842)
					(thickness 0.1524)
				)
			)
		)
		(property "Value" ""
			(at 0 0 270)
			(layer "F.Fab")
			(effects
				(font
					(size 1.27 1.27)
				)
			)
		)
		(duplicate_pad_numbers_are_jumpers no)
		(fp_line
			(start -2.286 7.366)
			(end -1.60147 7.366)
			(stroke
				(width 0.1524)
				(type default)
			)
			(layer "F.SilkS")
		)
		(fp_line
			(start -2.286 7.366)
			(end -2.286 1.632712)
			(stroke
				(width 0.1524)
				(type default)
			)
			(layer "F.SilkS")
		)
		(fp_line
			(start 2.286 7.366)
			(end 1.600708 7.366)
			(stroke
				(width 0.1524)
				(type default)
			)
			(layer "F.SilkS")
		)
		(fp_line
			(start 2.286 7.366)
			(end 2.286 1.63195)
			(stroke
				(width 0.1524)
				(type default)
			)
			(layer "F.SilkS")
		)
		(fp_line
			(start -2.563114 1.633728)
			(end -1.6002 1.633728)
			(stroke
				(width 0.1524)
				(type default)
			)
			(layer "F.SilkS")
		)
		(fp_line
			(start 2.504948 1.633728)
			(end 1.6002 1.633728)
			(stroke
				(width 0.1524)
				(type default)
			)
			(layer "F.SilkS")
		)
		(fp_line
			(start -2.563114 -1.616456)
			(end -2.563114 1.633728)
			(stroke
				(width 0.1524)
				(type default)
			)
			(layer "F.SilkS")
		)
		(fp_line
			(start -1.6002 -1.616456)
			(end -2.563114 -1.616456)
			(stroke
				(width 0.1524)
				(type default)
			)
			(layer "F.SilkS")
		)
		(fp_line
			(start 1.6002 -1.616456)
			(end 2.504948 -1.616456)
			(stroke
				(width 0.1524)
				(type default)
			)
			(layer "F.SilkS")
		)
		(fp_line
			(start 2.504948 -1.616456)
			(end 2.504948 1.633728)
			(stroke
				(width 0.1524)
				(type default)
			)
			(layer "F.SilkS")
		)
		(fp_rect
			(start -2.286 7.366)
			(end 2.286 -0.254)
			(stroke
				(width 0)
				(type default)
			)
			(fill no)
			(layer "F.CrtYd")
		)
		(fp_line
			(start -2.286 7.366)
			(end -2.286 -0.254)
			(stroke
				(width 0.1)
				(type default)
			)
			(layer "F.Fab")
		)
		(fp_line
			(start 2.286 7.366)
			(end -2.286 7.366)
			(stroke
				(width 0.1)
				(type default)
			)
			(layer "F.Fab")
		)
		(fp_line
			(start -2.286 -0.254)
			(end 2.286 -0.254)
			(stroke
				(width 0.1)
				(type default)
			)
			(layer "F.Fab")
		)
		(fp_line
			(start 2.286 -0.254)
			(end 2.286 7.366)
			(stroke
				(width 0.1)
				(type default)
			)
			(layer "F.Fab")
		)
		(pad "1" smd rect
			(at 0 0 270)
			(size 2.54 3.048)
			(layers "F.Cu" "F.Mask" "F.Paste")
			(net "PVCCMCP_CPU1")
		)
		(pad "2" smd rect
			(at 0 7.112 270)
			(size 2.54 3.048)
			(layers "F.Cu" "F.Mask" "F.Paste")
			(net "GND")
		)
	)
	(footprint ""
		(layer "F.Cu")
		(at 36.425886 -85.6996 -90)
		(property "Reference" "RT10"
			(at 0 0 270)
			(layer "F.SilkS")
			(hide yes)
			(effects
				(font
					(size 1.27 1.27)
				)
			)
		)
		(property "Value" "*"
			(at -0.0254 -2.6289 270)
			(unlocked yes)
			(layer "F.Fab")
			(hide yes)
			(effects
				(font
					(size 1.27 1.016)
					(thickness 0.1524)
				)
			)
		)
		(property "Device Type" "1R3F-GP_RCL_GP-1R3F-GP,64.1R00A"
			(at -0.0254 -4.1529 270)
			(unlocked yes)
			(layer "F.Fab")
			(hide yes)
			(effects
				(font
					(size 1.27 1.016)
					(thickness 0.1524)
				)
			)
		)
		(duplicate_pad_numbers_are_jumpers no)
		(fp_line
			(start -0.4826 0)
			(end -0.2032 0)
			(stroke
				(width 0.2032)
				(type default)
			)
			(layer "F.SilkS")
		)
		(fp_line
			(start 0.2032 0)
			(end 0.4826 0)
			(stroke
				(width 0.2032)
				(type default)
			)
			(layer "F.SilkS")
		)
		(fp_rect
			(start -0.5842 1.3335)
			(end 0.5842 -1.3335)
			(stroke
				(width 0)
				(type default)
			)
			(fill no)
			(layer "F.CrtYd")
		)
		(fp_rect
			(start -0.5842 1.3335)
			(end 0.5842 -1.3335)
			(stroke
				(width 0)
				(type default)
			)
			(fill no)
			(layer "F.Fab")
		)
		(pad "1" smd custom
			(at 0 -0.762 270)
			(size 0.2159 0.2159)
			(layers "F.Cu" "F.Mask" "F.Paste")
			(net "VR_PVCCIN_CPU1_PHASE5_RC")
			(options
				(clearance outline)
				(anchor circle)
			)
			(primitives
				(gr_poly
					(pts
						(arc
							(start -0.3302 -0.4318)
							(mid -0.402042 -0.402042)
							(end -0.4318 -0.3302)
						)
						(arc
							(start -0.4318 0.3302)
							(mid -0.402042 0.402042)
							(end -0.3302 0.4318)
						)
						(arc
							(start 0.3302 0.4318)
							(mid 0.402042 0.402042)
							(end 0.4318 0.3302)
						)
						(arc
							(start 0.4318 -0.3302)
							(mid 0.402042 -0.402042)
							(end 0.3302 -0.4318)
						)
					)
					(width 0)
					(fill yes)
				)
			)
		)
		(pad "2" smd custom
			(at 0 0.762 270)
			(size 0.2159 0.2159)
			(layers "F.Cu" "F.Mask" "F.Paste")
			(net "GND")
			(options
				(clearance outline)
				(anchor circle)
			)
			(primitives
				(gr_poly
					(pts
						(arc
							(start -0.3302 -0.4318)
							(mid -0.402042 -0.402042)
							(end -0.4318 -0.3302)
						)
						(arc
							(start -0.4318 0.3302)
							(mid -0.402042 0.402042)
							(end -0.3302 0.4318)
						)
						(arc
							(start 0.3302 0.4318)
							(mid 0.402042 0.402042)
							(end 0.4318 0.3302)
						)
						(arc
							(start 0.4318 -0.3302)
							(mid 0.402042 -0.402042)
							(end 0.3302 -0.4318)
						)
					)
					(width 0)
					(fill yes)
				)
			)
		)
	)
)
